(kicad_pcb
	(version 20260206)
	(generator "pcbnew")
	(generator_version "10.0")
	(general
		(thickness 1.6)
		(legacy_teardrops no)
	)
	(paper "A4")
	(title_block
		(title "Bryce Canyon_R.DPB_16317-1_OCP.brd")
		(comment 1 "Bryce Canyon / footprints 238-243 of 2099")
	)
	(layers
		(0 "F.Cu" signal "TOP")
		(4 "In1.Cu" signal "L2GND")
		(6 "In2.Cu" signal "L3")
		(8 "In3.Cu" signal "L4VCC")
		(10 "In4.Cu" signal "L5VCC")
		(12 "In5.Cu" signal "L6")
		(14 "In6.Cu" signal "L7GND")
		(2 "B.Cu" signal "BOTTOM")
		(9 "F.Adhes" user "F.Adhesive")
		(11 "B.Adhes" user "B.Adhesive")
		(13 "F.Paste" user "Package Geometry/Pastemask Top")
		(15 "B.Paste" user "Package Geometry/Pastemask Bottom")
		(5 "F.SilkS" user "Ref Des/Silkscreen Top")
		(7 "B.SilkS" user "Ref Des/Silkscreen Bottom")
		(1 "F.Mask" user "Board Geometry/Soldermask Top")
		(3 "B.Mask" user "Board Geometry/Soldermask Bottom")
		(17 "Dwgs.User" user "User.Drawings")
		(19 "Cmts.User" user "User.Comments")
		(21 "Eco1.User" user "User.Eco1")
		(23 "Eco2.User" user "User.Eco2")
		(25 "Edge.Cuts" user "Board Geometry/Outline")
		(27 "Margin" user)
		(31 "F.CrtYd" user "Package Geometry/Place Bound Top")
		(29 "B.CrtYd" user "Package Geometry/Place Bound Bottom")
		(35 "F.Fab" user "Ref Des/Assembly Top")
		(33 "B.Fab" user "Ref Des/Assembly Bottom")
	)
	(footprint ""
		(layer "F.Cu")
		(at 218.515692 -104.671368)
		(property "Reference" "R15"
			(at 0 0 0)
			(layer "F.SilkS")
			(hide yes)
			(effects
				(font
					(size 1.27 1.27)
				)
			)
		)
		(property "Value" "1KR2F-3-GP"
			(at 0.064008 -3.993896 0)
			(unlocked yes)
			(layer "F.Fab")
			(hide yes)
			(effects
				(font
					(size 1.016 1.016)
					(thickness 0.1524)
				)
			)
		)
		(property "Device Type" "R402H16"
			(at 0.064008 -5.517896 0)
			(unlocked yes)
			(layer "F.Fab")
			(hide yes)
			(effects
				(font
					(size 1.016 1.016)
					(thickness 0.1524)
				)
			)
		)
		(duplicate_pad_numbers_are_jumpers no)
		(fp_line
			(start -0.508 -0.9398)
			(end -0.508 0.9398)
			(stroke
				(width 0.1524)
				(type default)
			)
			(layer "F.SilkS")
		)
		(fp_line
			(start 0.508 -0.9398)
			(end -0.508 -0.9398)
			(stroke
				(width 0.1524)
				(type default)
			)
			(layer "F.SilkS")
		)
		(fp_rect
			(start -0.508 0.9398)
			(end 0.508 -0.9398)
			(stroke
				(width 0)
				(type default)
			)
			(fill no)
			(layer "F.CrtYd")
		)
		(fp_rect
			(start -0.508 0.9398)
			(end 0.508 -0.9398)
			(stroke
				(width 0)
				(type default)
			)
			(fill no)
			(layer "F.Fab")
		)
		(pad "1" smd custom
			(at 0 -0.4445)
			(size 0.1397 0.1397)
			(layers "F.Cu" "F.Mask" "F.Paste")
			(net "P3V3_STBY_B")
			(options
				(clearance outline)
				(anchor circle)
			)
			(primitives
				(gr_poly
					(pts
						(arc
							(start -0.1778 -0.2794)
							(mid -0.249642 -0.249642)
							(end -0.2794 -0.1778)
						)
						(arc
							(start -0.2794 0.1778)
							(mid -0.249642 0.249642)
							(end -0.1778 0.2794)
						)
						(arc
							(start 0.1778 0.2794)
							(mid 0.249642 0.249642)
							(end 0.2794 0.1778)
						)
						(arc
							(start 0.2794 -0.1778)
							(mid 0.249642 -0.249642)
							(end 0.1778 -0.2794)
						)
					)
					(width 0)
					(fill yes)
				)
			)
		)
		(pad "2" smd custom
			(at 0 0.4445)
			(size 0.1397 0.1397)
			(layers "F.Cu" "F.Mask" "F.Paste")
			(net "I2C_BMC_A_EXP_B_SDA")
			(options
				(clearance outline)
				(anchor circle)
			)
			(primitives
				(gr_poly
					(pts
						(arc
							(start -0.1778 -0.2794)
							(mid -0.249642 -0.249642)
							(end -0.2794 -0.1778)
						)
						(arc
							(start -0.2794 0.1778)
							(mid -0.249642 0.249642)
							(end -0.1778 0.2794)
						)
						(arc
							(start 0.1778 0.2794)
							(mid 0.249642 0.249642)
							(end 0.2794 0.1778)
						)
						(arc
							(start 0.2794 -0.1778)
							(mid 0.249642 -0.249642)
							(end 0.1778 -0.2794)
						)
					)
					(width 0)
					(fill yes)
				)
			)
		)
	)
	(footprint ""
		(layer "F.Cu")
		(at 286.639 -329.3618 -90)
		(property "Reference" "R162"
			(at 0 0 270)
			(layer "F.SilkS")
			(hide yes)
			(effects
				(font
					(size 1.27 1.27)
				)
			)
		)
		(property "Value" "4K7R2F-GP"
			(at 0.064008 -3.993896 270)
			(unlocked yes)
			(layer "F.Fab")
			(hide yes)
			(effects
				(font
					(size 1.016 1.016)
					(thickness 0.1524)
				)
			)
		)
		(property "Device Type" "R402H16"
			(at 0.064008 -5.517896 270)
			(unlocked yes)
			(layer "F.Fab")
			(hide yes)
			(effects
				(font
					(size 1.016 1.016)
					(thickness 0.1524)
				)
			)
		)
		(duplicate_pad_numbers_are_jumpers no)
		(fp_line
			(start -0.508 -0.9398)
			(end -0.508 0.9398)
			(stroke
				(width 0.1524)
				(type default)
			)
			(layer "F.SilkS")
		)
		(fp_line
			(start 0.508 -0.9398)
			(end -0.508 -0.9398)
			(stroke
				(width 0.1524)
				(type default)
			)
			(layer "F.SilkS")
		)
		(fp_rect
			(start -0.508 0.9398)
			(end 0.508 -0.9398)
			(stroke
				(width 0)
				(type default)
			)
			(fill no)
			(layer "F.CrtYd")
		)
		(fp_rect
			(start -0.508 0.9398)
			(end 0.508 -0.9398)
			(stroke
				(width 0)
				(type default)
			)
			(fill no)
			(layer "F.Fab")
		)
		(pad "1" smd custom
			(at 0 -0.4445 270)
			(size 0.1397 0.1397)
			(layers "F.Cu" "F.Mask" "F.Paste")
			(net "P3V3_IN")
			(options
				(clearance outline)
				(anchor circle)
			)
			(primitives
				(gr_poly
					(pts
						(arc
							(start -0.1778 -0.2794)
							(mid -0.249642 -0.249642)
							(end -0.2794 -0.1778)
						)
						(arc
							(start -0.2794 0.1778)
							(mid -0.249642 0.249642)
							(end -0.1778 0.2794)
						)
						(arc
							(start 0.1778 0.2794)
							(mid 0.249642 0.249642)
							(end 0.2794 0.1778)
						)
						(arc
							(start 0.2794 -0.1778)
							(mid 0.249642 -0.249642)
							(end 0.1778 -0.2794)
						)
					)
					(width 0)
					(fill yes)
				)
			)
		)
		(pad "2" smd custom
			(at 0 0.4445 270)
			(size 0.1397 0.1397)
			(layers "F.Cu" "F.Mask" "F.Paste")
			(net "PWM_OUT_D")
			(options
				(clearance outline)
				(anchor circle)
			)
			(primitives
				(gr_poly
					(pts
						(arc
							(start -0.1778 -0.2794)
							(mid -0.249642 -0.249642)
							(end -0.2794 -0.1778)
						)
						(arc
							(start -0.2794 0.1778)
							(mid -0.249642 0.249642)
							(end -0.1778 0.2794)
						)
						(arc
							(start 0.1778 0.2794)
							(mid 0.249642 0.249642)
							(end 0.2794 0.1778)
						)
						(arc
							(start 0.2794 -0.1778)
							(mid 0.249642 -0.249642)
							(end 0.1778 -0.2794)
						)
					)
					(width 0)
					(fill yes)
				)
			)
		)
	)
	(footprint ""
		(layer "F.Cu")
		(at 430.403 -131.826 180)
		(property "Reference" "R570"
			(at 0 0 180)
			(layer "F.SilkS")
			(hide yes)
			(effects
				(font
					(size 1.27 1.27)
				)
			)
		)
		(property "Value" "0R2J-2-GP"
			(at 0.064008 -3.993896 180)
			(unlocked yes)
			(layer "F.Fab")
			(hide yes)
			(effects
				(font
					(size 1.016 1.016)
					(thickness 0.1524)
				)
			)
		)
		(property "Device Type" "R402H16"
			(at 0.064008 -5.517896 180)
			(unlocked yes)
			(layer "F.Fab")
			(hide yes)
			(effects
				(font
					(size 1.016 1.016)
					(thickness 0.1524)
				)
			)
		)
		(duplicate_pad_numbers_are_jumpers no)
		(fp_line
			(start 0.508 -0.9398)
			(end -0.508 -0.9398)
			(stroke
				(width 0.1524)
				(type default)
			)
			(layer "F.SilkS")
		)
		(fp_line
			(start -0.508 -0.9398)
			(end -0.508 0.9398)
			(stroke
				(width 0.1524)
				(type default)
			)
			(layer "F.SilkS")
		)
		(fp_rect
			(start -0.508 0.9398)
			(end 0.508 -0.9398)
			(stroke
				(width 0)
				(type default)
			)
			(fill no)
			(layer "F.CrtYd")
		)
		(fp_rect
			(start -0.508 0.9398)
			(end 0.508 -0.9398)
			(stroke
				(width 0)
				(type default)
			)
			(fill no)
			(layer "F.Fab")
		)
		(pad "1" smd custom
			(at 0 -0.4445 180)
			(size 0.1397 0.1397)
			(layers "F.Cu" "F.Mask" "F.Paste")
			(net "SW_HDD_G21")
			(options
				(clearance outline)
				(anchor circle)
			)
			(primitives
				(gr_poly
					(pts
						(arc
							(start -0.1778 -0.2794)
							(mid -0.249642 -0.249642)
							(end -0.2794 -0.1778)
						)
						(arc
							(start -0.2794 0.1778)
							(mid -0.249642 0.249642)
							(end -0.1778 0.2794)
						)
						(arc
							(start 0.1778 0.2794)
							(mid 0.249642 0.249642)
							(end 0.2794 0.1778)
						)
						(arc
							(start 0.2794 -0.1778)
							(mid 0.249642 -0.249642)
							(end 0.1778 -0.2794)
						)
					)
					(width 0)
					(fill yes)
				)
			)
		)
		(pad "2" smd custom
			(at 0 0.4445 180)
			(size 0.1397 0.1397)
			(layers "F.Cu" "F.Mask" "F.Paste")
			(net "SW_HDD_R21")
			(options
				(clearance outline)
				(anchor circle)
			)
			(primitives
				(gr_poly
					(pts
						(arc
							(start -0.1778 -0.2794)
							(mid -0.249642 -0.249642)
							(end -0.2794 -0.1778)
						)
						(arc
							(start -0.2794 0.1778)
							(mid -0.249642 0.249642)
							(end -0.1778 0.2794)
						)
						(arc
							(start 0.1778 0.2794)
							(mid 0.249642 0.249642)
							(end 0.2794 0.1778)
						)
						(arc
							(start 0.2794 -0.1778)
							(mid 0.249642 -0.249642)
							(end 0.1778 -0.2794)
						)
					)
					(width 0)
					(fill yes)
				)
			)
		)
	)
	(footprint ""
		(layer "F.Cu")
		(at 251.572522 -360.146346 90)
		(property "Reference" "R1043"
			(at 0 0 90)
			(layer "F.SilkS")
			(hide yes)
			(effects
				(font
					(size 1.27 1.27)
				)
			)
		)
		(property "Value" "100KR2F-L1-GP"
			(at 0.064008 -3.993896 90)
			(unlocked yes)
			(layer "F.Fab")
			(hide yes)
			(effects
				(font
					(size 1.016 1.016)
					(thickness 0.1524)
				)
			)
		)
		(property "Device Type" "R402H16"
			(at 0.064008 -5.517896 90)
			(unlocked yes)
			(layer "F.Fab")
			(hide yes)
			(effects
				(font
					(size 1.016 1.016)
					(thickness 0.1524)
				)
			)
		)
		(duplicate_pad_numbers_are_jumpers no)
		(fp_line
			(start 0.508 -0.9398)
			(end -0.508 -0.9398)
			(stroke
				(width 0.1524)
				(type default)
			)
			(layer "F.SilkS")
		)
		(fp_line
			(start -0.508 -0.9398)
			(end -0.508 0.9398)
			(stroke
				(width 0.1524)
				(type default)
			)
			(layer "F.SilkS")
		)
		(fp_rect
			(start -0.508 0.9398)
			(end 0.508 -0.9398)
			(stroke
				(width 0)
				(type default)
			)
			(fill no)
			(layer "F.CrtYd")
		)
		(fp_rect
			(start -0.508 0.9398)
			(end 0.508 -0.9398)
			(stroke
				(width 0)
				(type default)
			)
			(fill no)
			(layer "F.Fab")
		)
		(pad "1" smd custom
			(at 0 -0.4445 90)
			(size 0.1397 0.1397)
			(layers "F.Cu" "F.Mask" "F.Paste")
			(net "MB3_VCAP_R")
			(options
				(clearance outline)
				(anchor circle)
			)
			(primitives
				(gr_poly
					(pts
						(arc
							(start -0.1778 -0.2794)
							(mid -0.249642 -0.249642)
							(end -0.2794 -0.1778)
						)
						(arc
							(start -0.2794 0.1778)
							(mid -0.249642 0.249642)
							(end -0.1778 0.2794)
						)
						(arc
							(start 0.1778 0.2794)
							(mid 0.249642 0.249642)
							(end 0.2794 0.1778)
						)
						(arc
							(start 0.2794 -0.1778)
							(mid 0.249642 -0.249642)
							(end 0.1778 -0.2794)
						)
					)
					(width 0)
					(fill yes)
				)
			)
		)
		(pad "2" smd custom
			(at 0 0.4445 90)
			(size 0.1397 0.1397)
			(layers "F.Cu" "F.Mask" "F.Paste")
			(net "MB3_ISET_R")
			(options
				(clearance outline)
				(anchor circle)
			)
			(primitives
				(gr_poly
					(pts
						(arc
							(start -0.1778 -0.2794)
							(mid -0.249642 -0.249642)
							(end -0.2794 -0.1778)
						)
						(arc
							(start -0.2794 0.1778)
							(mid -0.249642 0.249642)
							(end -0.1778 0.2794)
						)
						(arc
							(start 0.1778 0.2794)
							(mid 0.249642 0.249642)
							(end 0.2794 0.1778)
						)
						(arc
							(start 0.2794 -0.1778)
							(mid 0.249642 -0.249642)
							(end 0.1778 -0.2794)
						)
					)
					(width 0)
					(fill yes)
				)
			)
		)
	)
	(footprint ""
		(layer "F.Cu")
		(at 109.474 -260.858)
		(property "Reference" "Q12"
			(at 0 0 0)
			(layer "F.SilkS")
			(hide yes)
			(effects
				(font
					(size 1.27 1.27)
				)
			)
		)
		(property "Value" "AO4407AL-GP"
			(at -3.707384 -1.5367 0)
			(unlocked yes)
			(layer "F.Fab")
			(hide yes)
			(effects
				(font
					(size 1.016 1.016)
					(thickness 0.1524)
				)
			)
		)
		(property "Device Type" "SOIC8H69"
			(at -3.707384 -3.0607 0)
			(unlocked yes)
			(layer "F.Fab")
			(hide yes)
			(effects
				(font
					(size 1.016 1.016)
					(thickness 0.1524)
				)
			)
		)
		(duplicate_pad_numbers_are_jumpers no)
		(fp_line
			(start -2.7432 -1.4224)
			(end -2.7432 1.4224)
			(stroke
				(width 0.1524)
				(type default)
			)
			(layer "F.SilkS")
		)
		(fp_line
			(start -2.7432 1.4224)
			(end -2.6416 1.4224)
			(stroke
				(width 0.1524)
				(type default)
			)
			(layer "F.SilkS")
		)
		(fp_line
			(start -2.7432 1.4224)
			(end 2.1336 1.4224)
			(stroke
				(width 0.1524)
				(type default)
			)
			(layer "F.SilkS")
		)
		(fp_line
			(start -2.7178 -0.508)
			(end -2.1844 -0.0508)
			(stroke
				(width 0.1524)
				(type default)
			)
			(layer "F.SilkS")
		)
		(fp_line
			(start -2.6289 3.4417)
			(end -2.6289 1.4732)
			(stroke
				(width 0.381)
				(type default)
			)
			(layer "F.SilkS")
		)
		(fp_line
			(start -2.1844 -0.0508)
			(end -2.7178 0.508)
			(stroke
				(width 0.1524)
				(type default)
			)
			(layer "F.SilkS")
		)
		(fp_line
			(start 2.1336 -1.4224)
			(end -2.7432 -1.4224)
			(stroke
				(width 0.1524)
				(type default)
			)
			(layer "F.SilkS")
		)
		(fp_line
			(start 2.1336 1.4224)
			(end 2.1336 -1.4224)
			(stroke
				(width 0.1524)
				(type default)
			)
			(layer "F.SilkS")
		)
		(fp_poly
			(pts
				(xy -2.2098 -1.4224) (xy -2.2098 1.4224) (xy 2.2098 1.4224) (xy 2.2098 -1.4224)
			)
			(stroke
				(width 0)
				(type default)
			)
			(fill yes)
			(layer "F.SilkS")
		)
		(fp_rect
			(start -2.450084 2.999994)
			(end 2.450084 -2.999994)
			(stroke
				(width 0)
				(type default)
			)
			(fill no)
			(layer "F.CrtYd")
		)
		(fp_poly
			(pts
				(xy -2.8194 3.6322) (xy -2.8194 -3.6322) (xy 2.8194 -3.6322) (xy 2.8194 1.18364) (xy 2.450084 1.18364)
				(xy 2.450084 -2.999994) (xy -2.450084 -2.999994) (xy -2.450084 2.999994) (xy 2.450084 2.999994)
				(xy 2.450084 1.18618) (xy 2.8194 1.18618) (xy 2.8194 3.6322)
			)
			(stroke
				(width 0)
				(type default)
			)
			(fill no)
			(layer "F.CrtYd")
		)
		(fp_rect
			(start -2.8194 3.6322)
			(end 2.8194 -3.6322)
			(stroke
				(width 0)
				(type default)
			)
			(fill no)
			(layer "F.Fab")
		)
		(pad "1" smd rect
			(at -1.905 2.54)
			(size 0.635 1.651)
			(layers "F.Cu" "F.Mask" "F.Paste")
			(net "P12V_B")
		)
		(pad "2" smd rect
			(at -0.635 2.54)
			(size 0.635 1.651)
			(layers "F.Cu" "F.Mask" "F.Paste")
			(net "P12V_B")
		)
		(pad "3" smd rect
			(at 0.635 2.54)
			(size 0.635 1.651)
			(layers "F.Cu" "F.Mask" "F.Paste")
			(net "P12V_B")
		)
		(pad "4" smd rect
			(at 1.905 2.54)
			(size 0.635 1.651)
			(layers "F.Cu" "F.Mask" "F.Paste")
			(net "SW_HDD_N3")
		)
		(pad "5" smd rect
			(at 1.905 -2.54)
			(size 0.635 1.651)
			(layers "F.Cu" "F.Mask" "F.Paste")
			(net "P12V_HDD3")
		)
		(pad "6" smd rect
			(at 0.635 -2.54)
			(size 0.635 1.651)
			(layers "F.Cu" "F.Mask" "F.Paste")
			(net "P12V_HDD3")
		)
		(pad "7" smd rect
			(at -0.635 -2.54)
			(size 0.635 1.651)
			(layers "F.Cu" "F.Mask" "F.Paste")
			(net "P12V_HDD3")
		)
		(pad "8" smd rect
			(at -1.905 -2.54)
			(size 0.635 1.651)
			(layers "F.Cu" "F.Mask" "F.Paste")
			(net "P12V_HDD3")
		)
	)
	(footprint ""
		(layer "F.Cu")
		(at 78.359 -18.161 180)
		(property "Reference" "R684"
			(at 0 0 180)
			(layer "F.SilkS")
			(hide yes)
			(effects
				(font
					(size 1.27 1.27)
				)
			)
		)
		(property "Value" "200KR2F-L-GP"
			(at 0.064008 -3.993896 180)
			(unlocked yes)
			(layer "F.Fab")
			(hide yes)
			(effects
				(font
					(size 1.016 1.016)
					(thickness 0.1524)
				)
			)
		)
		(property "Device Type" "R402H16"
			(at 0.064008 -5.517896 180)
			(unlocked yes)
			(layer "F.Fab")
			(hide yes)
			(effects
				(font
					(size 1.016 1.016)
					(thickness 0.1524)
				)
			)
		)
		(duplicate_pad_numbers_are_jumpers no)
		(fp_line
			(start 0.508 -0.9398)
			(end -0.508 -0.9398)
			(stroke
				(width 0.1524)
				(type default)
			)
			(layer "F.SilkS")
		)
		(fp_line
			(start -0.508 -0.9398)
			(end -0.508 0.9398)
			(stroke
				(width 0.1524)
				(type default)
			)
			(layer "F.SilkS")
		)
		(fp_rect
			(start -0.508 0.9398)
			(end 0.508 -0.9398)
			(stroke
				(width 0)
				(type default)
			)
			(fill no)
			(layer "F.CrtYd")
		)
		(fp_rect
			(start -0.508 0.9398)
			(end 0.508 -0.9398)
			(stroke
				(width 0)
				(type default)
			)
			(fill no)
			(layer "F.Fab")
		)
		(pad "1" smd custom
			(at 0 -0.4445 180)
			(size 0.1397 0.1397)
			(layers "F.Cu" "F.Mask" "F.Paste")
			(net "SW_HDD_R26")
			(options
				(clearance outline)
				(anchor circle)
			)
			(primitives
				(gr_poly
					(pts
						(arc
							(start -0.1778 -0.2794)
							(mid -0.249642 -0.249642)
							(end -0.2794 -0.1778)
						)
						(arc
							(start -0.2794 0.1778)
							(mid -0.249642 0.249642)
							(end -0.1778 0.2794)
						)
						(arc
							(start 0.1778 0.2794)
							(mid 0.249642 0.249642)
							(end 0.2794 0.1778)
						)
						(arc
							(start 0.2794 -0.1778)
							(mid 0.249642 -0.249642)
							(end 0.1778 -0.2794)
						)
					)
					(width 0)
					(fill yes)
				)
			)
		)
		(pad "2" smd custom
			(at 0 0.4445 180)
			(size 0.1397 0.1397)
			(layers "F.Cu" "F.Mask" "F.Paste")
			(net "SW_HDD_N26")
			(options
				(clearance outline)
				(anchor circle)
			)
			(primitives
				(gr_poly
					(pts
						(arc
							(start -0.1778 -0.2794)
							(mid -0.249642 -0.249642)
							(end -0.2794 -0.1778)
						)
						(arc
							(start -0.2794 0.1778)
							(mid -0.249642 0.249642)
							(end -0.1778 0.2794)
						)
						(arc
							(start 0.1778 0.2794)
							(mid 0.249642 0.249642)
							(end 0.2794 0.1778)
						)
						(arc
							(start 0.2794 -0.1778)
							(mid 0.249642 -0.249642)
							(end 0.1778 -0.2794)
						)
					)
					(width 0)
					(fill yes)
				)
			)
		)
	)
)
